(kicad_pcb
	(version 20260206)
	(generator "pcbnew")
	(generator_version "10.0")
	(general
		(thickness 1.6)
		(legacy_teardrops no)
	)
	(paper "A4")
	(title_block
		(title "03242023_DA0F0TMBIJ0_F0T_Motherboard_J_brd_V01_OCP.brd")
		(comment 1 "Grand Teton / footprint 3900 of 6105 (J31), pads 113-224 of 291")
	)
	(layers
		(0 "F.Cu" signal "TOP")
		(4 "In1.Cu" signal "GND")
		(6 "In2.Cu" signal "IN1")
		(8 "In3.Cu" signal "GND1")
		(10 "In4.Cu" signal "IN2")
		(12 "In5.Cu" signal "GND2")
		(14 "In6.Cu" signal "IN3")
		(16 "In7.Cu" signal "GND3")
		(18 "In8.Cu" signal "VCC")
		(20 "In9.Cu" signal "VCC1")
		(22 "In10.Cu" signal "GND4")
		(24 "In11.Cu" signal "IN4")
		(26 "In12.Cu" signal "GND5")
		(28 "In13.Cu" signal "IN5")
		(30 "In14.Cu" signal "GND6")
		(32 "In15.Cu" signal "IN6")
		(34 "In16.Cu" signal "GND7")
		(2 "B.Cu" signal "BOTTOM")
		(9 "F.Adhes" user "F.Adhesive")
		(11 "B.Adhes" user "B.Adhesive")
		(13 "F.Paste" user "Package Geometry/Pastemask Top")
		(15 "B.Paste" user "Package Geometry/Pastemask Bottom")
		(5 "F.SilkS" user "Ref Des/Silkscreen Top")
		(7 "B.SilkS" user "Ref Des/Silkscreen Bottom")
		(1 "F.Mask" user "Board Geometry/Soldermask Top")
		(3 "B.Mask" user "Board Geometry/Soldermask Bottom")
		(17 "Dwgs.User" user "User.Drawings")
		(19 "Cmts.User" user "User.Comments")
		(21 "Eco1.User" user "User.Eco1")
		(23 "Eco2.User" user "User.Eco2")
		(25 "Edge.Cuts" user "Board Geometry/Outline")
		(27 "Margin" user)
		(31 "F.CrtYd" user "Package Geometry/Place Bound Top")
		(29 "B.CrtYd" user "Package Geometry/Place Bound Bottom")
		(35 "F.Fab" user "Ref Des/Assembly Top")
		(33 "B.Fab" user "Ref Des/Assembly Bottom")
	)
	(footprint ""
		(layer "F.Cu")
		(at 213.66988 -258.091686)
		(property "Reference" "J31"
			(at -3.683 -81.702148 0)
			(unlocked yes)
			(layer "F.SilkS")
			(effects
				(font
					(size 0.7874 0.5842)
					(thickness 0.1524)
				)
				(justify left)
			)
		)
		(property "Value" ""
			(at 0 0 0)
			(layer "F.Fab")
			(effects
				(font
					(size 1.27 1.27)
				)
			)
		)
		(duplicate_pad_numbers_are_jumpers no)
		(pad "113" smd rect
			(at -2.050034 36.975034 270)
			(size 0.519938 1.4986)
			(layers "F.Cu" "F.Mask" "F.Paste")
			(net "M_H_CPU1_SB_DQ<9>")
		)
		(pad "114" smd rect
			(at -2.050034 37.824918 270)
			(size 0.519938 1.4986)
			(layers "F.Cu" "F.Mask" "F.Paste")
			(net "GND")
		)
		(pad "115" smd rect
			(at -2.050034 38.675056 270)
			(size 0.519938 1.4986)
			(layers "F.Cu" "F.Mask" "F.Paste")
			(net "M_H_CPU1_SB_DQS_DP<1>")
		)
		(pad "116" smd rect
			(at -2.050034 39.52494 270)
			(size 0.519938 1.4986)
			(layers "F.Cu" "F.Mask" "F.Paste")
			(net "M_H_CPU1_SB_DQS_DN<1>")
		)
		(pad "117" smd rect
			(at -2.050034 40.375078 270)
			(size 0.519938 1.4986)
			(layers "F.Cu" "F.Mask" "F.Paste")
			(net "GND")
		)
		(pad "118" smd rect
			(at -2.050034 41.224962 270)
			(size 0.519938 1.4986)
			(layers "F.Cu" "F.Mask" "F.Paste")
			(net "M_H_CPU1_SB_DQ<12>")
		)
		(pad "119" smd rect
			(at -2.050034 42.0751 270)
			(size 0.519938 1.4986)
			(layers "F.Cu" "F.Mask" "F.Paste")
			(net "GND")
		)
		(pad "120" smd rect
			(at -2.050034 42.924984 270)
			(size 0.519938 1.4986)
			(layers "F.Cu" "F.Mask" "F.Paste")
			(net "M_H_CPU1_SB_DQ<13>")
		)
		(pad "121" smd rect
			(at -2.050034 43.775122 270)
			(size 0.519938 1.4986)
			(layers "F.Cu" "F.Mask" "F.Paste")
			(net "GND")
		)
		(pad "122" smd rect
			(at -2.050034 44.625006 270)
			(size 0.519938 1.4986)
			(layers "F.Cu" "F.Mask" "F.Paste")
			(net "M_H_CPU1_SB_DQ<16>")
		)
		(pad "123" smd rect
			(at -2.050034 45.47489 270)
			(size 0.519938 1.4986)
			(layers "F.Cu" "F.Mask" "F.Paste")
			(net "GND")
		)
		(pad "124" smd rect
			(at -2.050034 46.325028 270)
			(size 0.519938 1.4986)
			(layers "F.Cu" "F.Mask" "F.Paste")
			(net "M_H_CPU1_SB_DQ<17>")
		)
		(pad "125" smd rect
			(at -2.050034 47.174912 270)
			(size 0.519938 1.4986)
			(layers "F.Cu" "F.Mask" "F.Paste")
			(net "GND")
		)
		(pad "126" smd rect
			(at -2.050034 48.02505 270)
			(size 0.519938 1.4986)
			(layers "F.Cu" "F.Mask" "F.Paste")
			(net "M_H_CPU1_SB_DQS_DP<2>")
		)
		(pad "127" smd rect
			(at -2.050034 48.874934 270)
			(size 0.519938 1.4986)
			(layers "F.Cu" "F.Mask" "F.Paste")
			(net "M_H_CPU1_SB_DQS_DN<2>")
		)
		(pad "128" smd rect
			(at -2.050034 49.725072 270)
			(size 0.519938 1.4986)
			(layers "F.Cu" "F.Mask" "F.Paste")
			(net "GND")
		)
		(pad "129" smd rect
			(at -2.050034 50.574956 270)
			(size 0.519938 1.4986)
			(layers "F.Cu" "F.Mask" "F.Paste")
			(net "M_H_CPU1_SB_DQ<20>")
		)
		(pad "130" smd rect
			(at -2.050034 51.425094 270)
			(size 0.519938 1.4986)
			(layers "F.Cu" "F.Mask" "F.Paste")
			(net "GND")
		)
		(pad "131" smd rect
			(at -2.050034 52.274978 270)
			(size 0.519938 1.4986)
			(layers "F.Cu" "F.Mask" "F.Paste")
			(net "M_H_CPU1_SB_DQ<21>")
		)
		(pad "132" smd rect
			(at -2.050034 53.125116 270)
			(size 0.519938 1.4986)
			(layers "F.Cu" "F.Mask" "F.Paste")
			(net "GND")
		)
		(pad "133" smd rect
			(at -2.050034 53.975 270)
			(size 0.519938 1.4986)
			(layers "F.Cu" "F.Mask" "F.Paste")
			(net "M_H_CPU1_SB_DQ<24>")
		)
		(pad "134" smd rect
			(at -2.050034 54.824884 270)
			(size 0.519938 1.4986)
			(layers "F.Cu" "F.Mask" "F.Paste")
			(net "GND")
		)
		(pad "135" smd rect
			(at -2.050034 55.675022 270)
			(size 0.519938 1.4986)
			(layers "F.Cu" "F.Mask" "F.Paste")
			(net "M_H_CPU1_SB_DQ<25>")
		)
		(pad "136" smd rect
			(at -2.050034 56.524906 270)
			(size 0.519938 1.4986)
			(layers "F.Cu" "F.Mask" "F.Paste")
			(net "GND")
		)
		(pad "137" smd rect
			(at -2.050034 57.375044 270)
			(size 0.519938 1.4986)
			(layers "F.Cu" "F.Mask" "F.Paste")
			(net "M_H_CPU1_SB_DQS_DP<3>")
		)
		(pad "138" smd rect
			(at -2.050034 58.224928 270)
			(size 0.519938 1.4986)
			(layers "F.Cu" "F.Mask" "F.Paste")
			(net "M_H_CPU1_SB_DQS_DN<3>")
		)
		(pad "139" smd rect
			(at -2.050034 59.075066 270)
			(size 0.519938 1.4986)
			(layers "F.Cu" "F.Mask" "F.Paste")
			(net "GND")
		)
		(pad "140" smd rect
			(at -2.050034 59.92495 270)
			(size 0.519938 1.4986)
			(layers "F.Cu" "F.Mask" "F.Paste")
			(net "M_H_CPU1_SB_DQ<28>")
		)
		(pad "141" smd rect
			(at -2.050034 60.775088 270)
			(size 0.519938 1.4986)
			(layers "F.Cu" "F.Mask" "F.Paste")
			(net "GND")
		)
		(pad "142" smd rect
			(at -2.050034 61.624972 270)
			(size 0.519938 1.4986)
			(layers "F.Cu" "F.Mask" "F.Paste")
			(net "M_H_CPU1_SB_DQ<29>")
		)
		(pad "143" smd rect
			(at -2.050034 62.47511 270)
			(size 0.519938 1.4986)
			(layers "F.Cu" "F.Mask" "F.Paste")
			(net "GND")
		)
		(pad "144" smd rect
			(at -2.050034 63.324994 270)
			(size 0.519938 1.4986)
			(layers "F.Cu" "F.Mask" "F.Paste")
			(net "TP_CHH_CPU1_DIMM1_FRU_1")
		)
		(pad "145" smd rect
			(at 2.050034 -63.324994 270)
			(size 0.519938 1.4986)
			(layers "F.Cu" "F.Mask" "F.Paste")
			(net "P12V_S3_AUX_CPU1_NVDIMM")
		)
		(pad "146" smd rect
			(at 2.050034 -62.47511 270)
			(size 0.519938 1.4986)
			(layers "F.Cu" "F.Mask" "F.Paste")
			(net "P12V_S3_AUX_CPU1_NVDIMM")
		)
		(pad "147" smd rect
			(at 2.050034 -61.624972 270)
			(size 0.519938 1.4986)
			(layers "F.Cu" "F.Mask" "F.Paste")
			(net "PWRGD_CHH_CPU1_DIMM1")
		)
		(pad "148" smd rect
			(at 2.050034 -60.775088 270)
			(size 0.519938 1.4986)
			(layers "F.Cu" "F.Mask" "F.Paste")
			(net "PD_CHH_CPU1_DIMM1_SAA")
		)
		(pad "149" smd rect
			(at 2.050034 -59.92495 270)
			(size 0.519938 1.4986)
			(layers "F.Cu" "F.Mask" "F.Paste")
			(net "TP_CHH_CPU1_DIMM1_FRU_2")
		)
		(pad "150" smd rect
			(at 2.050034 -59.075066 270)
			(size 0.519938 1.4986)
			(layers "F.Cu" "F.Mask" "F.Paste")
			(net "TP_CHH_CPU1_DIMM1_FRU_3")
		)
		(pad "151" smd rect
			(at 2.050034 -58.224928 270)
			(size 0.519938 1.4986)
			(layers "F.Cu" "F.Mask" "F.Paste")
			(net "GND")
		)
		(pad "152" smd rect
			(at 2.050034 -57.375044 270)
			(size 0.519938 1.4986)
			(layers "F.Cu" "F.Mask" "F.Paste")
			(net "M_H_CPU1_SA_DQ<2>")
		)
		(pad "153" smd rect
			(at 2.050034 -56.524906 270)
			(size 0.519938 1.4986)
			(layers "F.Cu" "F.Mask" "F.Paste")
			(net "GND")
		)
		(pad "154" smd rect
			(at 2.050034 -55.675022 270)
			(size 0.519938 1.4986)
			(layers "F.Cu" "F.Mask" "F.Paste")
			(net "M_H_CPU1_SA_DQ<3>")
		)
		(pad "155" smd rect
			(at 2.050034 -54.824884 270)
			(size 0.519938 1.4986)
			(layers "F.Cu" "F.Mask" "F.Paste")
			(net "GND")
		)
		(pad "156" smd rect
			(at 2.050034 -53.975 270)
			(size 0.519938 1.4986)
			(layers "F.Cu" "F.Mask" "F.Paste")
			(net "M_H_CPU1_SA_DQS_DN<5>")
		)
		(pad "157" smd rect
			(at 2.050034 -53.125116 270)
			(size 0.519938 1.4986)
			(layers "F.Cu" "F.Mask" "F.Paste")
			(net "M_H_CPU1_SA_DQS_DP<5>")
		)
		(pad "158" smd rect
			(at 2.050034 -52.274978 270)
			(size 0.519938 1.4986)
			(layers "F.Cu" "F.Mask" "F.Paste")
			(net "GND")
		)
		(pad "159" smd rect
			(at 2.050034 -51.425094 270)
			(size 0.519938 1.4986)
			(layers "F.Cu" "F.Mask" "F.Paste")
			(net "M_H_CPU1_SA_DQ<6>")
		)
		(pad "160" smd rect
			(at 2.050034 -50.574956 270)
			(size 0.519938 1.4986)
			(layers "F.Cu" "F.Mask" "F.Paste")
			(net "GND")
		)
		(pad "161" smd rect
			(at 2.050034 -49.725072 270)
			(size 0.519938 1.4986)
			(layers "F.Cu" "F.Mask" "F.Paste")
			(net "M_H_CPU1_SA_DQ<7>")
		)
		(pad "162" smd rect
			(at 2.050034 -48.874934 270)
			(size 0.519938 1.4986)
			(layers "F.Cu" "F.Mask" "F.Paste")
			(net "GND")
		)
		(pad "163" smd rect
			(at 2.050034 -48.02505 270)
			(size 0.519938 1.4986)
			(layers "F.Cu" "F.Mask" "F.Paste")
			(net "M_H_CPU1_SA_DQ<10>")
		)
		(pad "164" smd rect
			(at 2.050034 -47.174912 270)
			(size 0.519938 1.4986)
			(layers "F.Cu" "F.Mask" "F.Paste")
			(net "GND")
		)
		(pad "165" smd rect
			(at 2.050034 -46.325028 270)
			(size 0.519938 1.4986)
			(layers "F.Cu" "F.Mask" "F.Paste")
			(net "M_H_CPU1_SA_DQ<11>")
		)
		(pad "166" smd rect
			(at 2.050034 -45.47489 270)
			(size 0.519938 1.4986)
			(layers "F.Cu" "F.Mask" "F.Paste")
			(net "GND")
		)
		(pad "167" smd rect
			(at 2.050034 -44.625006 270)
			(size 0.519938 1.4986)
			(layers "F.Cu" "F.Mask" "F.Paste")
			(net "M_H_CPU1_SA_DQS_DN<6>")
		)
		(pad "168" smd rect
			(at 2.050034 -43.775122 270)
			(size 0.519938 1.4986)
			(layers "F.Cu" "F.Mask" "F.Paste")
			(net "M_H_CPU1_SA_DQS_DP<6>")
		)
		(pad "169" smd rect
			(at 2.050034 -42.924984 270)
			(size 0.519938 1.4986)
			(layers "F.Cu" "F.Mask" "F.Paste")
			(net "GND")
		)
		(pad "170" smd rect
			(at 2.050034 -42.0751 270)
			(size 0.519938 1.4986)
			(layers "F.Cu" "F.Mask" "F.Paste")
			(net "M_H_CPU1_SA_DQ<14>")
		)
		(pad "171" smd rect
			(at 2.050034 -41.224962 270)
			(size 0.519938 1.4986)
			(layers "F.Cu" "F.Mask" "F.Paste")
			(net "GND")
		)
		(pad "172" smd rect
			(at 2.050034 -40.375078 270)
			(size 0.519938 1.4986)
			(layers "F.Cu" "F.Mask" "F.Paste")
			(net "M_H_CPU1_SA_DQ<15>")
		)
		(pad "173" smd rect
			(at 2.050034 -39.52494 270)
			(size 0.519938 1.4986)
			(layers "F.Cu" "F.Mask" "F.Paste")
			(net "GND")
		)
		(pad "174" smd rect
			(at 2.050034 -38.675056 270)
			(size 0.519938 1.4986)
			(layers "F.Cu" "F.Mask" "F.Paste")
			(net "M_H_CPU1_SA_DQ<18>")
		)
		(pad "175" smd rect
			(at 2.050034 -37.824918 270)
			(size 0.519938 1.4986)
			(layers "F.Cu" "F.Mask" "F.Paste")
			(net "GND")
		)
		(pad "176" smd rect
			(at 2.050034 -36.975034 270)
			(size 0.519938 1.4986)
			(layers "F.Cu" "F.Mask" "F.Paste")
			(net "M_H_CPU1_SA_DQ<19>")
		)
		(pad "177" smd rect
			(at 2.050034 -36.124896 270)
			(size 0.519938 1.4986)
			(layers "F.Cu" "F.Mask" "F.Paste")
			(net "GND")
		)
		(pad "178" smd rect
			(at 2.050034 -35.275012 270)
			(size 0.519938 1.4986)
			(layers "F.Cu" "F.Mask" "F.Paste")
			(net "M_H_CPU1_SA_DQS_DN<7>")
		)
		(pad "179" smd rect
			(at 2.050034 -34.425128 270)
			(size 0.519938 1.4986)
			(layers "F.Cu" "F.Mask" "F.Paste")
			(net "M_H_CPU1_SA_DQS_DP<7>")
		)
		(pad "180" smd rect
			(at 2.050034 -33.57499 270)
			(size 0.519938 1.4986)
			(layers "F.Cu" "F.Mask" "F.Paste")
			(net "GND")
		)
		(pad "181" smd rect
			(at 2.050034 -32.725106 270)
			(size 0.519938 1.4986)
			(layers "F.Cu" "F.Mask" "F.Paste")
			(net "M_H_CPU1_SA_DQ<22>")
		)
		(pad "182" smd rect
			(at 2.050034 -31.874968 270)
			(size 0.519938 1.4986)
			(layers "F.Cu" "F.Mask" "F.Paste")
			(net "GND")
		)
		(pad "183" smd rect
			(at 2.050034 -31.025084 270)
			(size 0.519938 1.4986)
			(layers "F.Cu" "F.Mask" "F.Paste")
			(net "M_H_CPU1_SA_DQ<23>")
		)
		(pad "184" smd rect
			(at 2.050034 -30.174946 270)
			(size 0.519938 1.4986)
			(layers "F.Cu" "F.Mask" "F.Paste")
			(net "GND")
		)
		(pad "185" smd rect
			(at 2.050034 -29.325062 270)
			(size 0.519938 1.4986)
			(layers "F.Cu" "F.Mask" "F.Paste")
			(net "M_H_CPU1_SA_DQ<26>")
		)
		(pad "186" smd rect
			(at 2.050034 -28.474924 270)
			(size 0.519938 1.4986)
			(layers "F.Cu" "F.Mask" "F.Paste")
			(net "GND")
		)
		(pad "187" smd rect
			(at 2.050034 -27.62504 270)
			(size 0.519938 1.4986)
			(layers "F.Cu" "F.Mask" "F.Paste")
			(net "M_H_CPU1_SA_DQ<27>")
		)
		(pad "188" smd rect
			(at 2.050034 -26.774902 270)
			(size 0.519938 1.4986)
			(layers "F.Cu" "F.Mask" "F.Paste")
			(net "GND")
		)
		(pad "189" smd rect
			(at 2.050034 -25.925018 270)
			(size 0.519938 1.4986)
			(layers "F.Cu" "F.Mask" "F.Paste")
			(net "M_H_CPU1_SA_DQS_DN<8>")
		)
		(pad "190" smd rect
			(at 2.050034 -25.07488 270)
			(size 0.519938 1.4986)
			(layers "F.Cu" "F.Mask" "F.Paste")
			(net "M_H_CPU1_SA_DQS_DP<8>")
		)
		(pad "191" smd rect
			(at 2.050034 -24.224996 270)
			(size 0.519938 1.4986)
			(layers "F.Cu" "F.Mask" "F.Paste")
			(net "GND")
		)
		(pad "192" smd rect
			(at 2.050034 -23.375112 270)
			(size 0.519938 1.4986)
			(layers "F.Cu" "F.Mask" "F.Paste")
			(net "M_H_CPU1_SA_DQ<30>")
		)
		(pad "193" smd rect
			(at 2.050034 -22.524974 270)
			(size 0.519938 1.4986)
			(layers "F.Cu" "F.Mask" "F.Paste")
			(net "GND")
		)
		(pad "194" smd rect
			(at 2.050034 -21.67509 270)
			(size 0.519938 1.4986)
			(layers "F.Cu" "F.Mask" "F.Paste")
			(net "M_H_CPU1_SA_DQ<31>")
		)
		(pad "195" smd rect
			(at 2.050034 -20.824952 270)
			(size 0.519938 1.4986)
			(layers "F.Cu" "F.Mask" "F.Paste")
			(net "GND")
		)
		(pad "196" smd rect
			(at 2.050034 -19.975068 270)
			(size 0.519938 1.4986)
			(layers "F.Cu" "F.Mask" "F.Paste")
			(net "M_H_CPU1_SA_CB<2>")
		)
		(pad "197" smd rect
			(at 2.050034 -19.12493 270)
			(size 0.519938 1.4986)
			(layers "F.Cu" "F.Mask" "F.Paste")
			(net "GND")
		)
		(pad "198" smd rect
			(at 2.050034 -18.275046 270)
			(size 0.519938 1.4986)
			(layers "F.Cu" "F.Mask" "F.Paste")
			(net "M_H_CPU1_SA_CB<3>")
		)
		(pad "199" smd rect
			(at 2.050034 -17.424908 270)
			(size 0.519938 1.4986)
			(layers "F.Cu" "F.Mask" "F.Paste")
			(net "GND")
		)
		(pad "200" smd rect
			(at 2.050034 -16.575024 270)
			(size 0.519938 1.4986)
			(layers "F.Cu" "F.Mask" "F.Paste")
			(net "M_H_CPU1_SA_DQS_DN<9>")
		)
		(pad "201" smd rect
			(at 2.050034 -15.724886 270)
			(size 0.519938 1.4986)
			(layers "F.Cu" "F.Mask" "F.Paste")
			(net "M_H_CPU1_SA_DQS_DP<9>")
		)
		(pad "202" smd rect
			(at 2.050034 -14.875002 270)
			(size 0.519938 1.4986)
			(layers "F.Cu" "F.Mask" "F.Paste")
			(net "GND")
		)
		(pad "203" smd rect
			(at 2.050034 -14.025118 270)
			(size 0.519938 1.4986)
			(layers "F.Cu" "F.Mask" "F.Paste")
			(net "M_H_CPU1_SA_CB<6>")
		)
		(pad "204" smd rect
			(at 2.050034 -13.17498 270)
			(size 0.519938 1.4986)
			(layers "F.Cu" "F.Mask" "F.Paste")
			(net "GND")
		)
		(pad "205" smd rect
			(at 2.050034 -12.325096 270)
			(size 0.519938 1.4986)
			(layers "F.Cu" "F.Mask" "F.Paste")
			(net "M_H_CPU1_SA_CB<7>")
		)
		(pad "206" smd rect
			(at 2.050034 -11.474958 270)
			(size 0.519938 1.4986)
			(layers "F.Cu" "F.Mask" "F.Paste")
			(net "GND")
		)
		(pad "207" smd rect
			(at 2.050034 -10.625074 270)
			(size 0.519938 1.4986)
			(layers "F.Cu" "F.Mask" "F.Paste")
			(net "RST_M_GH_CPU1_FPGA_N")
		)
		(pad "208" smd rect
			(at 2.050034 -9.774936 270)
			(size 0.519938 1.4986)
			(layers "F.Cu" "F.Mask" "F.Paste")
			(net "GND")
		)
		(pad "209" smd rect
			(at 2.050034 -8.925052 270)
			(size 0.519938 1.4986)
			(layers "F.Cu" "F.Mask" "F.Paste")
			(net "M_H_CPU1_SA_CS_N<1>")
		)
		(pad "210" smd rect
			(at 2.050034 -8.074914 270)
			(size 0.519938 1.4986)
			(layers "F.Cu" "F.Mask" "F.Paste")
			(net "GND")
		)
		(pad "211" smd rect
			(at 2.050034 -7.22503 270)
			(size 0.519938 1.4986)
			(layers "F.Cu" "F.Mask" "F.Paste")
			(net "M_H_CPU1_SA_CA<1>")
		)
		(pad "212" smd rect
			(at 2.050034 -6.374892 270)
			(size 0.519938 1.4986)
			(layers "F.Cu" "F.Mask" "F.Paste")
			(net "GND")
		)
		(pad "213" smd rect
			(at 2.050034 -5.525008 270)
			(size 0.519938 1.4986)
			(layers "F.Cu" "F.Mask" "F.Paste")
			(net "M_H_CPU1_SA_CA<3>")
		)
		(pad "214" smd rect
			(at 2.050034 -4.675124 270)
			(size 0.519938 1.4986)
			(layers "F.Cu" "F.Mask" "F.Paste")
			(net "GND")
		)
		(pad "215" smd rect
			(at 2.050034 -3.824986 270)
			(size 0.519938 1.4986)
			(layers "F.Cu" "F.Mask" "F.Paste")
			(net "M_H_CPU1_SA_CA<5>")
		)
		(pad "216" smd rect
			(at 2.050034 -2.975102 270)
			(size 0.519938 1.4986)
			(layers "F.Cu" "F.Mask" "F.Paste")
			(net "GND")
		)
		(pad "217" smd rect
			(at 2.050034 -2.124964 270)
			(size 0.519938 1.4986)
			(layers "F.Cu" "F.Mask" "F.Paste")
			(net "M_H_CPU1_CLK_DP<0>")
		)
		(pad "218" smd rect
			(at 2.050034 -1.27508 270)
			(size 0.519938 1.4986)
			(layers "F.Cu" "F.Mask" "F.Paste")
			(net "M_H_CPU1_CLK_DN<0>")
		)
		(pad "219" smd rect
			(at 2.050034 -0.424942 270)
			(size 0.519938 1.4986)
			(layers "F.Cu" "F.Mask" "F.Paste")
			(net "GND")
		)
		(pad "220" smd rect
			(at 2.050034 5.525008 270)
			(size 0.519938 1.4986)
			(layers "F.Cu" "F.Mask" "F.Paste")
			(net "TP_CHH_CPU1_DIMM1_FRU_4")
		)
		(pad "221" smd rect
			(at 2.050034 6.374892 270)
			(size 0.519938 1.4986)
			(layers "F.Cu" "F.Mask" "F.Paste")
			(net "M_H_CPU1_SB_CA<1>")
		)
		(pad "222" smd rect
			(at 2.050034 7.22503 270)
			(size 0.519938 1.4986)
			(layers "F.Cu" "F.Mask" "F.Paste")
			(net "GND")
		)
		(pad "223" smd rect
			(at 2.050034 8.074914 270)
			(size 0.519938 1.4986)
			(layers "F.Cu" "F.Mask" "F.Paste")
			(net "M_H_CPU1_SB_CA<3>")
		)
		(pad "224" smd rect
			(at 2.050034 8.925052 270)
			(size 0.519938 1.4986)
			(layers "F.Cu" "F.Mask" "F.Paste")
			(net "GND")
		)
	)
)
